G04 ================== begin FILE IDENTIFICATION RECORD ==================*
G04 Layout Name:  DA0T6MTH8C0_t6m_tray_bp_c_brd_103112_274.brd*
G04 Film Name:    smb.art*
G04 File Format:  Gerber RS274X*
G04 File Origin:  Cadence Allegro 16.3-S048*
G04 Origin Date:  Tue Nov 26 11:26:41 2013*
G04 *
G04 Layer:  DRAWING FORMAT/TITLE_BLOCK*
G04 Layer:  VIA CLASS/SOLDERMASK_BOTTOM*
G04 Layer:  PIN/SOLDERMASK_BOTTOM*
G04 Layer:  PACKAGE GEOMETRY/SOLDERMASK_BOTTOM*
G04 Layer:  MANUFACTURING/PHOTOPLOT_OUTLINE*
G04 Layer:  DRAWING FORMAT/TITLE_DATA_SMB*
G04 Layer:  BOARD GEOMETRY/SOLDERMASK_BOTTOM*
G04 *
G04 Offset:    (0.00 0.00)*
G04 Mirror:    No*
G04 Mode:      Positive*
G04 Rotation:  0*
G04 FullContactRelief:  No*
G04 UndefLineWidth:     6.00*
G04 ================== end FILE IDENTIFICATION RECORD ====================*
%FSLAX25Y25*MOIN*%
%IR0*IPPOS*OFA0.00000B0.00000*MIA0B0*SFA1.00000B1.00000*%
%ADD15R,.036X.201*%
%ADD20C,.03*%
%ADD34C,.04*%
%ADD26C,.05*%
%ADD11C,.07*%
%ADD10C,.034*%
%ADD33C,.053*%
%ADD21C,.062*%
%ADD16C,.063*%
%ADD35C,.055*%
%ADD38R,.04X.04*%
%ADD31C,.065*%
%ADD30C,.083*%
%ADD29C,.057*%
%ADD28R,.05X.05*%
%ADD22C,.058*%
%ADD17C,.067*%
%ADD13R,.07X.07*%
%ADD41C,.096*%
%ADD39R,.055X.055*%
%ADD18R,.067X.067*%
%ADD42R,.107X.43*%
%ADD23C,.12*%
%ADD27C,.105*%
%ADD36C,.124*%
%ADD25C,.232*%
%ADD40C,.143*%
%ADD12C,.162*%
%ADD24C,.217*%
%ADD19R,.377X.252*%
%ADD37C,.148*%
%ADD32O,.058X.083*%
%ADD14C,.158*%
%ADD43C,.02*%
%ADD44C,.006*%
%ADD45C,.1782*%
G75*
%LPD*%
G75*
G36*
G01X35634Y18504D02*
G02X-200I-17917J0D01*
G01Y42126D01*
G02X35634I17917J0D01*
G01Y18504D01*
G37*
G36*
G01X33664Y114173D02*
G02X1768I-15948J0D01*
G01Y137795D01*
G02X33664I15948J0D01*
G01Y114173D01*
G37*
G36*
G01X35626Y184006D02*
Y209843D01*
X6926D01*
Y184006D01*
X35626D01*
G37*
G36*
G01X201441Y209895D02*
X43632D01*
Y178895D01*
X201441D01*
Y209895D01*
G37*
G36*
G01X330161Y163386D02*
G02X298265I-15948J0D01*
G01Y187008D01*
G02X330161I15948J0D01*
G01Y163386D01*
G37*
G36*
G01X799609Y18504D02*
G02X767713I-15948J0D01*
G01Y42126D01*
G02X799609I15948J0D01*
G01Y18504D01*
G37*
G36*
G01X841972Y163386D02*
G02X810076I-15948J0D01*
G01Y187008D01*
G02X841972I15948J0D01*
G01Y163386D01*
G37*
G36*
G01X1117563Y18504D02*
G02X1085667I-15948J0D01*
G01Y42126D01*
G02X1117563I15948J0D01*
G01Y18504D01*
G37*
G36*
G01X1200240Y163386D02*
G02X1168344I-15948J0D01*
G01Y187008D01*
G02X1200240I15948J0D01*
G01Y163386D01*
G37*
G36*
G01X1688429Y18504D02*
G02X1652595I-17917J0D01*
G01Y42126D01*
G02X1688429I17917J0D01*
G01Y18504D01*
G37*
%LPC*%
G75*
G36*
G01X8351Y127903D02*
G02X27081I9365J9892D01*
G03X26416Y126359I1462J-1545D01*
G01Y114173D01*
G02X9016I-8700J0D01*
G01Y126359D01*
G03X8351Y127903I-2127J-1D01*
G37*
G36*
G01X304848Y177116D02*
G02X323578I9365J9892D01*
G03X322913Y175572I1462J-1545D01*
G01Y163386D01*
G02X305513I-8700J0D01*
G01Y175572D01*
G03X304848Y177116I-2127J-1D01*
G37*
G36*
G01X774296Y32234D02*
G02X793026I9365J9892D01*
G03X792361Y30690I1462J-1545D01*
G01Y18504D01*
G02X774961I-8700J0D01*
G01Y30690D01*
G03X774296Y32234I-2127J-1D01*
G37*
G36*
G01X816659Y177116D02*
G02X835389I9365J9892D01*
G03X834724Y175572I1462J-1545D01*
G01Y163386D01*
G02X817324I-8700J0D01*
G01Y175572D01*
G03X816659Y177116I-2127J-1D01*
G37*
G36*
G01X1092250Y32234D02*
G02X1110980I9365J9892D01*
G03X1110315Y30690I1462J-1545D01*
G01Y18504D01*
G02X1092915I-8700J0D01*
G01Y30690D01*
G03X1092250Y32234I-2127J-1D01*
G37*
G36*
G01X1174927Y177116D02*
G02X1193657I9365J9892D01*
G03X1192992Y175572I1462J-1545D01*
G01Y163386D01*
G02X1175592I-8700J0D01*
G01Y175572D01*
G03X1174927Y177116I-2127J-1D01*
G37*
G54D45*
X17717Y18504D03*
X1670512D03*
%LPD*%
G75*
G54D10*
X8221Y28000D03*
Y9008D03*
X4287Y18504D03*
X17717Y5074D03*
X27213Y28000D03*
X31147Y18504D03*
X27213Y9008D03*
X17717Y31934D03*
X1661016Y28000D03*
Y9008D03*
X1657082Y18504D03*
X1670512Y5074D03*
X1680008Y28000D03*
X1683942Y18504D03*
X1680008Y9008D03*
X1670512Y31934D03*
G54D11*
X9088Y80158D03*
Y91958D03*
X109288Y92458D03*
Y103958D03*
G54D20*
X68400Y141200D03*
X64500Y165200D03*
X99100Y127470D03*
X89400Y165300D03*
X102400Y59600D03*
X111958Y73600D03*
X121958Y70900D03*
X116958Y68600D03*
X106958Y68500D03*
X102590Y115680D03*
X115400Y120270D03*
X107390Y125110D03*
X119800Y124390D03*
X108900Y137300D03*
X114300Y134900D03*
X119700Y132400D03*
X111500Y129900D03*
X105800Y165400D03*
X128600Y114510D03*
X132500Y110100D03*
X125000Y126400D03*
X141400Y164800D03*
X129000D03*
X169200Y165200D03*
X155500Y164800D03*
X183300Y164700D03*
X346800Y113500D03*
X345400Y107600D03*
X346200Y102500D03*
X350700Y121642D03*
X345900Y125100D03*
X347350Y143750D03*
X346906Y137693D03*
X362500Y97100D03*
X357800Y114657D03*
X357600Y108561D03*
X356861Y102961D03*
X414900Y6500D03*
X463435Y79865D03*
X453900Y92300D03*
X453300Y86800D03*
X451100Y81400D03*
X452100Y97000D03*
X452000Y102200D03*
X488000Y89800D03*
X477630Y88900D03*
X525700Y99300D03*
X519400Y96400D03*
X520439Y91000D03*
X516500Y87442D03*
X571500Y7500D03*
X604200Y107400D03*
X614900Y90157D03*
X615600Y95139D03*
X625600Y95400D03*
X625700Y90100D03*
X615500Y100157D03*
X622658Y112158D03*
X622200Y120258D03*
X615500Y105157D03*
X626173Y148400D03*
X617949Y147000D03*
X659310Y72900D03*
X664310D03*
X654400Y92100D03*
Y97100D03*
X672638Y93290D03*
X666614Y121000D03*
X661614D03*
X671063Y125930D03*
X676063D03*
X680300Y75600D03*
X689723Y89400D03*
X689311Y96311D03*
X677638Y93290D03*
X689961Y122030D03*
X694961D03*
X680612Y129600D03*
X685612D03*
X701100Y16900D03*
X701670Y97100D03*
Y92100D03*
X740300Y87300D03*
X735807Y96593D03*
X724400Y105600D03*
X729400D03*
X730310Y115390D03*
X725310D03*
X761929Y72900D03*
X756929D03*
X752480Y92830D03*
X747480D03*
X764153Y96153D03*
X745905Y120452D03*
X750905D03*
X764803Y120330D03*
X760410Y124730D03*
X755410D03*
X778200Y92130D03*
Y97130D03*
X776032Y101968D03*
X769803Y120330D03*
X1223200Y99000D03*
X1216500Y119500D03*
X1216700Y114400D03*
X1216500Y108300D03*
X1216400Y102600D03*
X1226900Y119561D03*
Y114043D03*
X1227000Y108361D03*
X1227100Y102861D03*
X1219600Y129400D03*
X1219400Y123900D03*
X1211200Y144900D03*
X1217405Y143895D03*
X1229800Y96400D03*
X1238100Y127900D03*
X1323000Y99239D03*
X1321400Y92800D03*
X1321500Y82600D03*
X1322500Y87800D03*
X1359000Y91000D03*
X1387400Y87242D03*
X1389900Y97600D03*
X1395200Y99500D03*
X1391000Y92400D03*
X1442400Y8200D03*
X1494200Y97800D03*
X1495000Y92800D03*
X1484700Y93057D03*
X1485000Y98057D03*
X1484900Y103257D03*
X1492300Y117558D03*
X1484800Y109357D03*
X1492042Y126358D03*
X1495800Y147800D03*
X1487600Y147000D03*
X1524478Y97100D03*
Y92100D03*
X1534388Y72900D03*
X1529388D03*
X1550500Y75500D03*
X1542716Y93290D03*
X1547716D03*
X1531692Y121000D03*
X1536692D03*
X1546141Y125930D03*
X1550690Y129600D03*
X1541141Y125930D03*
X1570800Y18900D03*
X1571748Y92100D03*
Y97100D03*
X1559802Y89400D03*
X1559389Y96311D03*
X1565039Y122030D03*
X1560039D03*
X1555690Y129600D03*
X1594478Y105600D03*
X1595388Y115390D03*
X1617558Y92830D03*
X1610379Y87300D03*
X1605885Y96593D03*
X1599478Y105600D03*
X1600388Y115390D03*
X1615983Y120452D03*
X1627007Y72900D03*
X1632007D03*
X1622558Y92830D03*
X1634231Y96153D03*
X1620983Y120452D03*
X1639881Y120330D03*
X1634881D03*
X1625488Y124730D03*
X1630488D03*
X1648278Y97130D03*
Y92130D03*
X1646110Y101968D03*
G54D12*
X17717Y18504D03*
X1670512D03*
G54D30*
X392795Y56653D03*
X542087Y56654D03*
X655453Y132244D03*
X702697D03*
X730295D03*
X777539D03*
X1262874Y56654D03*
X1412166Y56653D03*
X1525531Y132244D03*
X1572775D03*
X1600374D03*
X1647618D03*
G54D21*
X85866Y72835D03*
Y104331D03*
G54D40*
X639283Y108622D03*
Y167677D03*
X793693Y108622D03*
Y167677D03*
X1509362Y108622D03*
Y167677D03*
X1663772Y108622D03*
Y167677D03*
G54D13*
X19088Y80158D03*
Y91958D03*
X119288Y92458D03*
Y103958D03*
G54D22*
X81929Y76772D03*
Y68898D03*
X89803Y76772D03*
Y68898D03*
X81929Y100394D03*
Y92520D03*
Y84646D03*
X89803Y100394D03*
Y92520D03*
Y84646D03*
X81929Y108268D03*
X89803D03*
G54D31*
X383642Y40532D03*
Y79902D03*
X396122Y99587D03*
X383642Y119272D03*
Y158642D03*
X417382Y99587D03*
X405964Y178327D03*
X439744Y99587D03*
Y138957D03*
Y178327D03*
X532934Y40532D03*
Y79902D03*
Y119272D03*
Y158642D03*
X545414Y99587D03*
X555256Y178327D03*
X566674Y99587D03*
X589036D03*
Y138957D03*
Y178327D03*
X1253721Y40532D03*
Y79902D03*
Y119272D03*
Y158642D03*
X1266201Y99587D03*
X1276043Y178327D03*
X1287461Y99587D03*
X1309823D03*
Y138957D03*
Y178327D03*
X1403012Y40532D03*
Y79902D03*
Y119272D03*
Y158642D03*
X1415492Y99587D03*
X1436752D03*
X1425334Y178327D03*
X1459114Y99587D03*
Y138957D03*
Y178327D03*
G54D14*
X17716Y114173D03*
X314213Y163386D03*
X783661Y18504D03*
X826024Y163386D03*
X1101615Y18504D03*
X1184292Y163386D03*
G54D32*
X430591Y56653D03*
X579883Y56654D03*
X1300670D03*
X1449962Y56653D03*
G54D23*
X109500Y41000D03*
X1009800Y81300D03*
X1636400Y43100D03*
G54D41*
X641212Y132244D03*
X791764D03*
X1511291D03*
X1661843D03*
G54D24*
X306772Y19685D03*
Y41850D03*
X612047Y19685D03*
Y41850D03*
X1176851Y19685D03*
Y41850D03*
X1482126Y19685D03*
Y41850D03*
G54D42*
X1676417Y102756D03*
G54D33*
X439744Y60217D03*
X589036D03*
X1309823D03*
X1459114D03*
G54D15*
X8741Y194095D03*
X13741D03*
X18741D03*
X23741D03*
X28741D03*
X33741D03*
G54D43*
G01X1683504Y165354D02*
Y190512D01*
G03X1675630Y198386I-7874J0D01*
G01X1503898D01*
X1502406Y198679D01*
X1501137Y199516D01*
X1500279Y200772D01*
X1499930Y202268D01*
X1499661Y203554D01*
X1498808Y204831D01*
X1497530Y205685D01*
X1496024Y205984D01*
X1468465D01*
G03X1464528Y202047I0J-3937D01*
G01Y200000D01*
G02X1460591Y196063I-3937J0D01*
G01X1401535D01*
G02X1397598Y200000I0J3937D01*
G01Y202047D01*
G03X1393661Y205984I-3937J0D01*
G01X1319173D01*
G03X1315236Y202047I0J-3937D01*
G01Y200000D01*
G02X1311299Y196063I-3937J0D01*
G01X1252244D01*
G02X1248307Y200000I0J3937D01*
G01Y202047D01*
G03X1244370Y205984I-3937J0D01*
G01X807047D01*
X805541Y205685D01*
X804263Y204831D01*
X803410Y203554D01*
X803141Y202268D01*
X802792Y200772D01*
X801934Y199516D01*
X800665Y198679D01*
X799173Y198386D01*
X633819D01*
X632327Y198679D01*
X631058Y199516D01*
X630200Y200772D01*
X629851Y202268D01*
X629582Y203554D01*
X628729Y204831D01*
X627451Y205685D01*
X625945Y205984D01*
X598386D01*
G03X594449Y202047I0J-3937D01*
G01Y200000D01*
G02X590512Y196063I-3937J0D01*
G01X531457D01*
G02X527520Y200000I0J3937D01*
G01Y202047D01*
G03X523583Y205984I-3937J0D01*
G01X449094D01*
G03X445157Y202047I0J-3937D01*
G01Y200000D01*
G02X441220Y196063I-3937J0D01*
G01X382165D01*
G02X378228Y200000I0J3937D01*
G01Y202047D01*
G03X374291Y205984I-3937J0D01*
G01X228661D01*
G03X220787Y198110I0J-7874D01*
G01Y170551D01*
G02X216850Y166614I-3937J0D01*
G01X208976D01*
G02X205039Y170551I0J3937D01*
G01Y203937D01*
X199134Y209842D01*
X49803D01*
X43898Y203937D01*
Y167913D01*
G02X41142I-1378J0D01*
G01Y203937D01*
X37205Y207874D01*
X35236Y209842D01*
X5906D01*
X3937Y207874D01*
X0Y203937D01*
Y7874D01*
G03X7874Y0I7874J0D01*
G01X1680354D01*
G03X1688228Y7874I0J7874D01*
G01Y39370D01*
G03X1686260Y41339I-1969J0D01*
G01X1685472D01*
G02X1683504Y43307I0J1968D01*
G01Y122047D01*
G03X1681535Y124016I-1969J0D01*
G01X1675236D01*
G02X1673268Y125984I0J1968D01*
G01Y161417D01*
G02X1675236Y163386I1968J1D01*
G01X1681535D01*
G03X1683504Y165354I1J1968D01*
G01X10433Y114173D02*
Y128497D01*
G02X25000I7283J9298D01*
G01Y114173D01*
G02X10433I-7284J0D01*
G01X306929Y163386D02*
Y177710D01*
G02X321496I7283J9298D01*
G01Y163386D01*
G02X306929I-7283J0D01*
G01X776772Y18504D02*
Y32533D01*
G02X790551I6889J9593D01*
G01Y18504D01*
G02X776772I-6890J0D01*
G01X819134Y163386D02*
Y177415D01*
G02X832913I6890J9593D01*
G01Y163386D01*
G02X819134I-6889J0D01*
G01X1094331Y18504D02*
Y32828D01*
G02X1108898I7283J9298D01*
G01Y18504D01*
G02X1094331I-7283J0D01*
G01X1177008Y163386D02*
Y177710D01*
G02X1191575I7284J9298D01*
G01Y163386D01*
G02X1177008I-7283J0D01*
G54D25*
X306772Y67913D03*
X612047D03*
X1176851D03*
X1482126D03*
G54D16*
X40827Y29528D03*
Y147638D03*
G54D34*
X466654Y7874D03*
Y29922D03*
Y24410D03*
Y18898D03*
Y13386D03*
Y51969D03*
Y46457D03*
Y40945D03*
Y35433D03*
X474528Y8268D03*
X482402Y7874D03*
X490276Y8268D03*
X474528Y30315D03*
X482402Y29922D03*
X490276Y30315D03*
X474528Y24803D03*
X482402Y24410D03*
X490276Y24803D03*
X474528Y19292D03*
X482402Y18898D03*
X490276Y19292D03*
X474528Y13780D03*
X482402Y13386D03*
X490276Y13780D03*
X474528Y52362D03*
X482402Y51969D03*
X490276Y52362D03*
X474528Y46851D03*
X482402Y46457D03*
X490276Y46851D03*
X474528Y41339D03*
X482402Y40945D03*
X490276Y41339D03*
X474528Y35827D03*
X482402Y35433D03*
X490276Y35827D03*
X498150Y7874D03*
Y29922D03*
X506024Y30315D03*
X498150Y24410D03*
X506024Y24803D03*
X498150Y18898D03*
X506024Y19292D03*
X498150Y13386D03*
X506024Y13780D03*
X498150Y51969D03*
X506024Y52362D03*
X498150Y46457D03*
X506024Y46851D03*
X498150Y40945D03*
X506024Y41339D03*
X498150Y35433D03*
X506024Y35827D03*
X649173Y7874D03*
Y29922D03*
Y24410D03*
Y18898D03*
Y13386D03*
Y51969D03*
Y46457D03*
Y40945D03*
Y35433D03*
X657047Y8268D03*
X664921Y7874D03*
X672795Y8268D03*
X657047Y30315D03*
X664921Y29922D03*
X672795Y30315D03*
X657047Y24803D03*
X664921Y24410D03*
X672795Y24803D03*
X657047Y19292D03*
X664921Y18898D03*
X672795Y19292D03*
X657047Y13780D03*
X664921Y13386D03*
X672795Y13780D03*
X657047Y52362D03*
X664921Y51969D03*
X672795Y52362D03*
X657047Y46851D03*
X664921Y46457D03*
X672795Y46851D03*
X657047Y41339D03*
X664921Y40945D03*
X672795Y41339D03*
X657047Y35827D03*
X664921Y35433D03*
X672795Y35827D03*
X680669Y7874D03*
Y29922D03*
X688543Y30315D03*
X680669Y24410D03*
X688543Y24803D03*
X680669Y18898D03*
X688543Y19292D03*
X680669Y13386D03*
X688543Y13780D03*
X680669Y51969D03*
X688543Y52362D03*
X680669Y46457D03*
X688543Y46851D03*
X680669Y40945D03*
X688543Y41339D03*
X680669Y35433D03*
X688543Y35827D03*
X1336733Y7874D03*
X1344607Y8268D03*
X1336733Y29922D03*
X1344607Y30315D03*
X1336733Y24410D03*
X1344607Y24803D03*
X1336733Y18898D03*
X1344607Y19292D03*
X1336733Y13386D03*
X1344607Y13780D03*
X1336733Y51969D03*
X1344607Y52362D03*
X1336733Y46457D03*
X1344607Y46851D03*
X1336733Y40945D03*
X1344607Y41339D03*
X1336733Y35433D03*
X1344607Y35827D03*
X1352481Y7874D03*
X1360355Y8268D03*
X1352481Y29922D03*
X1360355Y30315D03*
X1352481Y24410D03*
X1360355Y24803D03*
X1352481Y18898D03*
X1360355Y19292D03*
X1352481Y13386D03*
X1360355Y13780D03*
X1352481Y51969D03*
X1360355Y52362D03*
X1352481Y46457D03*
X1360355Y46851D03*
X1352481Y40945D03*
X1360355Y41339D03*
X1352481Y35433D03*
X1360355Y35827D03*
X1368229Y7874D03*
Y29922D03*
X1376103Y30315D03*
X1368229Y24410D03*
X1376103Y24803D03*
X1368229Y18898D03*
X1376103Y19292D03*
X1368229Y13386D03*
X1376103Y13780D03*
X1368229Y51969D03*
X1376103Y52362D03*
X1368229Y46457D03*
X1376103Y46851D03*
X1368229Y40945D03*
X1376103Y41339D03*
X1368229Y35433D03*
X1376103Y35827D03*
X1519252Y7874D03*
X1527126Y8268D03*
X1519252Y29922D03*
X1527126Y30315D03*
X1519252Y24410D03*
X1527126Y24803D03*
X1519252Y18898D03*
X1527126Y19292D03*
X1519252Y13386D03*
X1527126Y13780D03*
X1519252Y51969D03*
X1527126Y52362D03*
X1519252Y46457D03*
X1527126Y46851D03*
X1519252Y40945D03*
X1527126Y41339D03*
X1519252Y35433D03*
X1527126Y35827D03*
X1535000Y7874D03*
X1542874Y8268D03*
X1550748Y7874D03*
X1535000Y29922D03*
X1542874Y30315D03*
X1550748Y29922D03*
X1535000Y24410D03*
X1542874Y24803D03*
X1550748Y24410D03*
X1535000Y18898D03*
X1542874Y19292D03*
X1550748Y18898D03*
X1535000Y13386D03*
X1542874Y13780D03*
X1550748Y13386D03*
X1535000Y51969D03*
X1542874Y52362D03*
X1550748Y51969D03*
X1535000Y46457D03*
X1542874Y46851D03*
X1550748Y46457D03*
X1535000Y40945D03*
X1542874Y41339D03*
X1550748Y40945D03*
X1535000Y35433D03*
X1542874Y35827D03*
X1550748Y35433D03*
X1558622Y30315D03*
Y24803D03*
Y19292D03*
Y13780D03*
Y52362D03*
Y46851D03*
Y41339D03*
Y35827D03*
G54D44*
G01X457212Y-338900D02*
Y-343900D01*
G01X455755Y-338900D02*
X458669D01*
G01X463579Y-343900D02*
X461045D01*
Y-338900D01*
X463579D01*
G01X462565Y-341317D02*
X461045D01*
G01X466145Y-338900D02*
Y-343900D01*
X468679D01*
G01X472512Y-344067D02*
X472385Y-343983D01*
Y-343817D01*
X472512Y-343733D01*
X472639Y-343817D01*
Y-343983D01*
X472512Y-344067D01*
G01Y-341817D02*
X472385Y-341733D01*
Y-341567D01*
X472512Y-341483D01*
X472639Y-341567D01*
Y-341733D01*
X472512Y-341817D01*
G01X477295Y-345567D02*
X476662Y-344733D01*
X476345Y-343900D01*
Y-340567D01*
X476662Y-339733D01*
X477295Y-338900D01*
G01X482712D02*
X482205Y-339067D01*
X481825Y-339483D01*
X481572Y-339983D01*
X481382Y-340650D01*
X481319Y-341400D01*
X481382Y-342150D01*
X481572Y-342817D01*
X481825Y-343317D01*
X482205Y-343733D01*
X482712Y-343900D01*
X483219Y-343733D01*
X483599Y-343317D01*
X483852Y-342817D01*
X484042Y-342150D01*
X484105Y-341400D01*
X484042Y-340650D01*
X483852Y-339983D01*
X483599Y-339483D01*
X483219Y-339067D01*
X482712Y-338900D01*
G01X486419Y-342900D02*
X486799Y-343483D01*
X487305Y-343817D01*
X487875Y-343900D01*
X488382Y-343817D01*
X488889Y-343400D01*
X489205Y-342900D01*
X489269Y-342400D01*
X489142Y-341817D01*
X488699Y-341400D01*
X488255Y-341233D01*
X487685D01*
G01X488255D02*
X488635Y-340983D01*
X488952Y-340567D01*
X489079Y-340067D01*
X488952Y-339567D01*
X488635Y-339150D01*
X488065Y-338900D01*
X487495Y-338983D01*
X486925Y-339317D01*
G01X493229Y-345567D02*
X493862Y-344733D01*
X494179Y-343900D01*
Y-340567D01*
X493862Y-339733D01*
X493229Y-338900D01*
G01X496619Y-342900D02*
X496999Y-343483D01*
X497505Y-343817D01*
X498075Y-343900D01*
X498582Y-343817D01*
X499089Y-343400D01*
X499405Y-342900D01*
X499469Y-342400D01*
X499342Y-341817D01*
X498899Y-341400D01*
X498455Y-341233D01*
X497885D01*
G01X498455D02*
X498835Y-340983D01*
X499152Y-340567D01*
X499279Y-340067D01*
X499152Y-339567D01*
X498835Y-339150D01*
X498265Y-338900D01*
X497695Y-338983D01*
X497125Y-339317D01*
G01X501909Y-339733D02*
X502289Y-339233D01*
X502732Y-338983D01*
X503239Y-338900D01*
X503872Y-339067D01*
X504315Y-339483D01*
X504442Y-339983D01*
X504379Y-340483D01*
X504125Y-340900D01*
X502859Y-341733D01*
X502289Y-342317D01*
X501909Y-343150D01*
X501782Y-343900D01*
X504442D01*
G01X508085D02*
X508212Y-342817D01*
X508402Y-341900D01*
X508655Y-341067D01*
X508972Y-340150D01*
X509479Y-338900D01*
X506945D01*
G01X512489Y-342233D02*
X514135D01*
G01X517209Y-339733D02*
X517589Y-339233D01*
X518032Y-338983D01*
X518539Y-338900D01*
X519172Y-339067D01*
X519615Y-339483D01*
X519742Y-339983D01*
X519679Y-340483D01*
X519425Y-340900D01*
X518159Y-341733D01*
X517589Y-342317D01*
X517209Y-343150D01*
X517082Y-343900D01*
X519742D01*
G01X522119Y-342900D02*
X522499Y-343483D01*
X523005Y-343817D01*
X523575Y-343900D01*
X524082Y-343817D01*
X524589Y-343400D01*
X524905Y-342900D01*
X524969Y-342400D01*
X524842Y-341817D01*
X524399Y-341400D01*
X523955Y-341233D01*
X523385D01*
G01X523955D02*
X524335Y-340983D01*
X524652Y-340567D01*
X524779Y-340067D01*
X524652Y-339567D01*
X524335Y-339150D01*
X523765Y-338900D01*
X523195Y-338983D01*
X522625Y-339317D01*
G01X529372Y-343900D02*
Y-338900D01*
X527029Y-342483D01*
X530195D01*
G01X532319Y-343150D02*
X532699Y-343567D01*
X533142Y-343817D01*
X533712Y-343900D01*
X534282Y-343733D01*
X534725Y-343400D01*
X535042Y-342817D01*
X535105Y-342150D01*
X534979Y-341483D01*
X534662Y-341067D01*
X534219Y-340733D01*
X533775Y-340650D01*
X533332Y-340733D01*
X532762Y-341067D01*
X532952Y-338900D01*
X534662D01*
G01X542709Y-343900D02*
Y-338900D01*
X545115D01*
G01X544229Y-341317D02*
X542709D01*
G01X547429Y-343900D02*
X549012Y-338900D01*
X550595Y-343900D01*
G01X550025Y-342150D02*
X547999D01*
G01X552782Y-343900D02*
X555442Y-338900D01*
G01X552782D02*
X555442Y-343900D01*
G01X559212Y-344067D02*
X559085Y-343983D01*
Y-343817D01*
X559212Y-343733D01*
X559339Y-343817D01*
Y-343983D01*
X559212Y-344067D01*
G01Y-341817D02*
X559085Y-341733D01*
Y-341567D01*
X559212Y-341483D01*
X559339Y-341567D01*
Y-341733D01*
X559212Y-341817D01*
G01X563995Y-345567D02*
X563362Y-344733D01*
X563045Y-343900D01*
Y-340567D01*
X563362Y-339733D01*
X563995Y-338900D01*
G01X569412D02*
X568905Y-339067D01*
X568525Y-339483D01*
X568272Y-339983D01*
X568082Y-340650D01*
X568019Y-341400D01*
X568082Y-342150D01*
X568272Y-342817D01*
X568525Y-343317D01*
X568905Y-343733D01*
X569412Y-343900D01*
X569919Y-343733D01*
X570299Y-343317D01*
X570552Y-342817D01*
X570742Y-342150D01*
X570805Y-341400D01*
X570742Y-340650D01*
X570552Y-339983D01*
X570299Y-339483D01*
X569919Y-339067D01*
X569412Y-338900D01*
G01X573119Y-342900D02*
X573499Y-343483D01*
X574005Y-343817D01*
X574575Y-343900D01*
X575082Y-343817D01*
X575589Y-343400D01*
X575905Y-342900D01*
X575969Y-342400D01*
X575842Y-341817D01*
X575399Y-341400D01*
X574955Y-341233D01*
X574385D01*
G01X574955D02*
X575335Y-340983D01*
X575652Y-340567D01*
X575779Y-340067D01*
X575652Y-339567D01*
X575335Y-339150D01*
X574765Y-338900D01*
X574195Y-338983D01*
X573625Y-339317D01*
G01X579929Y-345567D02*
X580562Y-344733D01*
X580879Y-343900D01*
Y-340567D01*
X580562Y-339733D01*
X579929Y-338900D01*
G01X583319Y-342900D02*
X583699Y-343483D01*
X584205Y-343817D01*
X584775Y-343900D01*
X585282Y-343817D01*
X585789Y-343400D01*
X586105Y-342900D01*
X586169Y-342400D01*
X586042Y-341817D01*
X585599Y-341400D01*
X585155Y-341233D01*
X584585D01*
G01X585155D02*
X585535Y-340983D01*
X585852Y-340567D01*
X585979Y-340067D01*
X585852Y-339567D01*
X585535Y-339150D01*
X584965Y-338900D01*
X584395Y-338983D01*
X583825Y-339317D01*
G01X588735Y-343317D02*
X589179Y-343733D01*
X589685Y-343900D01*
X590192Y-343733D01*
X590635Y-343233D01*
X590952Y-342483D01*
X591079Y-341733D01*
Y-340817D01*
X590952Y-340067D01*
X590635Y-339400D01*
X590255Y-339067D01*
X589812Y-338900D01*
X589305Y-339067D01*
X588925Y-339400D01*
X588672Y-339900D01*
X588545Y-340567D01*
X588672Y-341150D01*
X588989Y-341733D01*
X589369Y-342067D01*
X589812Y-342150D01*
X590319Y-341983D01*
X590699Y-341567D01*
X591079Y-340817D01*
G01X594785Y-343900D02*
X594912Y-342817D01*
X595102Y-341900D01*
X595355Y-341067D01*
X595672Y-340150D01*
X596179Y-338900D01*
X593645D01*
G01X599189Y-342233D02*
X600835D01*
G01X603719Y-342900D02*
X604099Y-343483D01*
X604605Y-343817D01*
X605175Y-343900D01*
X605682Y-343817D01*
X606189Y-343400D01*
X606505Y-342900D01*
X606569Y-342400D01*
X606442Y-341817D01*
X605999Y-341400D01*
X605555Y-341233D01*
X604985D01*
G01X605555D02*
X605935Y-340983D01*
X606252Y-340567D01*
X606379Y-340067D01*
X606252Y-339567D01*
X605935Y-339150D01*
X605365Y-338900D01*
X604795Y-338983D01*
X604225Y-339317D01*
G01X609009Y-341817D02*
X609452Y-341233D01*
X609832Y-340900D01*
X610339Y-340733D01*
X610782Y-340900D01*
X611099Y-341233D01*
X611352Y-341733D01*
X611415Y-342317D01*
X611352Y-342817D01*
X611099Y-343317D01*
X610719Y-343733D01*
X610275Y-343900D01*
X609769Y-343733D01*
X609325Y-343233D01*
X609072Y-342483D01*
X609009Y-341650D01*
X609135Y-340567D01*
X609325Y-339983D01*
X609642Y-339400D01*
X610085Y-338983D01*
X610529Y-338900D01*
X610972Y-339067D01*
X611289Y-339483D01*
G01X615312Y-343900D02*
Y-338900D01*
X614552Y-339900D01*
G01Y-343900D02*
X616072D01*
G01X621172D02*
Y-338900D01*
X618829Y-342483D01*
X621995D01*
G01X445212Y-273900D02*
Y-348900D01*
X945212D01*
Y-273900D01*
X445212D01*
G01X640212D02*
Y-348900D01*
G01Y-323900D02*
X743212D01*
Y-298900D01*
G01X640212D02*
X743212D01*
G01Y-273900D02*
Y-348900D01*
G01X745212Y-273900D02*
Y-348900D01*
G01X750719Y-333900D02*
Y-328900D01*
X751985D01*
X752492Y-329150D01*
X752872Y-329483D01*
X753189Y-329983D01*
X753442Y-330567D01*
X753505Y-331400D01*
X753442Y-332233D01*
X753189Y-332817D01*
X752872Y-333317D01*
X752492Y-333650D01*
X751985Y-333900D01*
X750719D01*
G01X755629D02*
X757212Y-328900D01*
X758795Y-333900D01*
G01X758225Y-332150D02*
X756199D01*
G01X762312Y-328900D02*
Y-333900D01*
G01X760855Y-328900D02*
X763769D01*
G01X768679Y-333900D02*
X766145D01*
Y-328900D01*
X768679D01*
G01X767665Y-331317D02*
X766145D01*
G01X772512Y-334067D02*
X772385Y-333983D01*
Y-333817D01*
X772512Y-333733D01*
X772639Y-333817D01*
Y-333983D01*
X772512Y-334067D01*
G01Y-331817D02*
X772385Y-331733D01*
Y-331567D01*
X772512Y-331483D01*
X772639Y-331567D01*
Y-331733D01*
X772512Y-331817D01*
G01X745212Y-323900D02*
X945212D01*
G01X750845Y-308900D02*
Y-303900D01*
X752365D01*
X752872Y-304150D01*
X753252Y-304733D01*
X753379Y-305400D01*
X753252Y-306067D01*
X752935Y-306567D01*
X752365Y-306817D01*
X750845D01*
G01X756072Y-309067D02*
X758352Y-303900D01*
G01X760855Y-308900D02*
Y-303900D01*
X763769Y-308900D01*
Y-303900D01*
G01X767412Y-309067D02*
X767285Y-308983D01*
Y-308817D01*
X767412Y-308733D01*
X767539Y-308817D01*
Y-308983D01*
X767412Y-309067D01*
G01Y-306817D02*
X767285Y-306733D01*
Y-306567D01*
X767412Y-306483D01*
X767539Y-306567D01*
Y-306733D01*
X767412Y-306817D01*
G01X745212Y-298900D02*
X945212D01*
G01X750845Y-283900D02*
Y-278900D01*
X752365D01*
X752872Y-279150D01*
X753252Y-279733D01*
X753379Y-280400D01*
X753252Y-281067D01*
X752935Y-281567D01*
X752365Y-281817D01*
X750845D01*
G01X755945Y-283900D02*
Y-278900D01*
X757529D01*
X758035Y-279150D01*
X758352Y-279483D01*
X758479Y-280150D01*
X758352Y-280817D01*
X757972Y-281233D01*
X757529Y-281483D01*
X755945D01*
G01X757529D02*
X758479Y-283900D01*
G01X762312D02*
X761805Y-283817D01*
X761362Y-283483D01*
X760982Y-282983D01*
X760729Y-282400D01*
X760602Y-281733D01*
Y-281067D01*
X760729Y-280400D01*
X760982Y-279817D01*
X761362Y-279317D01*
X761805Y-278983D01*
X762312Y-278900D01*
X762819Y-278983D01*
X763262Y-279317D01*
X763642Y-279817D01*
X763895Y-280400D01*
X764022Y-281067D01*
Y-281733D01*
X763895Y-282400D01*
X763642Y-282983D01*
X763262Y-283483D01*
X762819Y-283817D01*
X762312Y-283900D01*
G01X766145Y-282900D02*
X766462Y-283400D01*
X766842Y-283733D01*
X767285Y-283900D01*
X767792Y-283733D01*
X768172Y-283400D01*
X768552Y-282900D01*
X768679Y-282233D01*
Y-278900D01*
G01X773779Y-283900D02*
X771245D01*
Y-278900D01*
X773779D01*
G01X772765Y-281317D02*
X771245D01*
G01X779005Y-279317D02*
X778625Y-279067D01*
X778182Y-278900D01*
X777675D01*
X777105Y-279150D01*
X776662Y-279567D01*
X776345Y-280067D01*
X776092Y-280900D01*
X776029Y-281650D01*
X776155Y-282400D01*
X776345Y-282900D01*
X776725Y-283400D01*
X777169Y-283733D01*
X777612Y-283900D01*
X778055D01*
X778499Y-283733D01*
X778879Y-283483D01*
X779195Y-283150D01*
G01X782712Y-278900D02*
Y-283900D01*
G01X781255Y-278900D02*
X784169D01*
G01X787812Y-284067D02*
X787685Y-283983D01*
Y-283817D01*
X787812Y-283733D01*
X787939Y-283817D01*
Y-283983D01*
X787812Y-284067D01*
G01Y-281817D02*
X787685Y-281733D01*
Y-281567D01*
X787812Y-281483D01*
X787939Y-281567D01*
Y-281733D01*
X787812Y-281817D01*
G01X860212Y-323900D02*
Y-348900D01*
G01X865845Y-333900D02*
Y-328900D01*
X867429D01*
X867935Y-329150D01*
X868252Y-329483D01*
X868379Y-330150D01*
X868252Y-330817D01*
X867872Y-331233D01*
X867429Y-331483D01*
X865845D01*
G01X867429D02*
X868379Y-333900D01*
G01X873479D02*
X870945D01*
Y-328900D01*
X873479D01*
G01X872465Y-331317D02*
X870945D01*
G01X875729Y-328900D02*
X877312Y-333900D01*
X878895Y-328900D01*
G01X882412Y-334067D02*
X882285Y-333983D01*
Y-333817D01*
X882412Y-333733D01*
X882539Y-333817D01*
Y-333983D01*
X882412Y-334067D01*
G01Y-331817D02*
X882285Y-331733D01*
Y-331567D01*
X882412Y-331483D01*
X882539Y-331567D01*
Y-331733D01*
X882412Y-331817D01*
G01X909212Y-323900D02*
Y-348900D01*
G01X-471400Y-391900D02*
Y1528800D01*
X2244200D01*
Y-391900D01*
X-471400D01*
G01X455917Y-335560D02*
X456544Y-336085D01*
X457249Y-336400D01*
X457875D01*
X458502Y-336085D01*
X458972Y-335560D01*
X459207Y-334825D01*
X459050Y-334090D01*
X458659Y-333460D01*
X457954Y-333040D01*
X457014Y-332830D01*
X456465Y-332410D01*
X456230Y-331675D01*
X456387Y-330940D01*
X456779Y-330415D01*
X457327Y-330100D01*
X457875D01*
X458424Y-330310D01*
X458894Y-330835D01*
G01X462217Y-336400D02*
Y-330100D01*
G01X465507D02*
Y-336400D01*
G01Y-333250D02*
X462217D01*
G01X469222Y-330100D02*
X471102D01*
G01X470162D02*
Y-336400D01*
G01X469222D02*
X471102D01*
G01X478029D02*
X474895D01*
Y-330100D01*
X478029D01*
G01X476775Y-333145D02*
X474895D01*
G01X480960Y-336400D02*
Y-330100D01*
X484564Y-336400D01*
Y-330100D01*
G01X488905Y-337555D02*
X489219Y-336190D01*
G01X495362Y-330100D02*
Y-336400D01*
G01X493560Y-330100D02*
X497164D01*
G01X499704Y-336400D02*
X501662Y-330100D01*
X503620Y-336400D01*
G01X502915Y-334195D02*
X500409D01*
G01X507022Y-330100D02*
X508902D01*
G01X507962D02*
Y-336400D01*
G01X507022D02*
X508902D01*
G01X511912Y-330100D02*
X513009Y-336400D01*
X514262Y-330100D01*
X515515Y-336400D01*
X516612Y-330100D01*
G01X518604Y-336400D02*
X520562Y-330100D01*
X522520Y-336400D01*
G01X521815Y-334195D02*
X519309D01*
G01X525060Y-336400D02*
Y-330100D01*
X528664Y-336400D01*
Y-330100D01*
G01X537895Y-336400D02*
Y-330100D01*
X539854D01*
X540480Y-330415D01*
X540872Y-330835D01*
X541029Y-331675D01*
X540872Y-332515D01*
X540402Y-333040D01*
X539854Y-333355D01*
X537895D01*
G01X539854D02*
X541029Y-336400D01*
G01X545762Y-336610D02*
X545605Y-336505D01*
Y-336295D01*
X545762Y-336190D01*
X545919Y-336295D01*
Y-336505D01*
X545762Y-336610D01*
G01X552062Y-336400D02*
X551435Y-336295D01*
X550887Y-335875D01*
X550417Y-335245D01*
X550104Y-334510D01*
X549947Y-333670D01*
Y-332830D01*
X550104Y-331990D01*
X550417Y-331255D01*
X550887Y-330625D01*
X551435Y-330205D01*
X552062Y-330100D01*
X552689Y-330205D01*
X553237Y-330625D01*
X553707Y-331255D01*
X554020Y-331990D01*
X554177Y-332830D01*
Y-333670D01*
X554020Y-334510D01*
X553707Y-335245D01*
X553237Y-335875D01*
X552689Y-336295D01*
X552062Y-336400D01*
G01X558362Y-336610D02*
X558205Y-336505D01*
Y-336295D01*
X558362Y-336190D01*
X558519Y-336295D01*
Y-336505D01*
X558362Y-336610D01*
G01X566385Y-330625D02*
X565915Y-330310D01*
X565367Y-330100D01*
X564740D01*
X564035Y-330415D01*
X563487Y-330940D01*
X563095Y-331570D01*
X562782Y-332620D01*
X562704Y-333565D01*
X562860Y-334510D01*
X563095Y-335140D01*
X563565Y-335770D01*
X564114Y-336190D01*
X564662Y-336400D01*
X565210D01*
X565759Y-336190D01*
X566229Y-335875D01*
X566620Y-335455D01*
G01X570962Y-336610D02*
X570805Y-336505D01*
Y-336295D01*
X570962Y-336190D01*
X571119Y-336295D01*
Y-336505D01*
X570962Y-336610D01*
G01X455839Y-326400D02*
Y-320100D01*
G01X458815D02*
X455839Y-323985D01*
G01X459285Y-326400D02*
X457170Y-322200D01*
G01X462139Y-320100D02*
Y-324615D01*
X462452Y-325560D01*
X463079Y-326190D01*
X463862Y-326400D01*
X464645Y-326190D01*
X465272Y-325560D01*
X465585Y-324615D01*
Y-320100D01*
G01X471729Y-326400D02*
X468595D01*
Y-320100D01*
X471729D01*
G01X470475Y-323145D02*
X468595D01*
G01X475522Y-320100D02*
X477402D01*
G01X476462D02*
Y-326400D01*
G01X475522D02*
X477402D01*
G01X487417Y-325560D02*
X488044Y-326085D01*
X488749Y-326400D01*
X489375D01*
X490002Y-326085D01*
X490472Y-325560D01*
X490707Y-324825D01*
X490550Y-324090D01*
X490159Y-323460D01*
X489454Y-323040D01*
X488514Y-322830D01*
X487965Y-322410D01*
X487730Y-321675D01*
X487887Y-320940D01*
X488279Y-320415D01*
X488827Y-320100D01*
X489375D01*
X489924Y-320310D01*
X490394Y-320835D01*
G01X493717Y-326400D02*
Y-320100D01*
G01X497007D02*
Y-326400D01*
G01Y-323250D02*
X493717D01*
G01X499704Y-326400D02*
X501662Y-320100D01*
X503620Y-326400D01*
G01X502915Y-324195D02*
X500409D01*
G01X506160Y-326400D02*
Y-320100D01*
X509764Y-326400D01*
Y-320100D01*
G01X518917Y-326400D02*
Y-320100D01*
G01X522207D02*
Y-326400D01*
G01Y-323250D02*
X518917D01*
G01X525217Y-325560D02*
X525844Y-326085D01*
X526549Y-326400D01*
X527175D01*
X527802Y-326085D01*
X528272Y-325560D01*
X528507Y-324825D01*
X528350Y-324090D01*
X527959Y-323460D01*
X527254Y-323040D01*
X526314Y-322830D01*
X525765Y-322410D01*
X525530Y-321675D01*
X525687Y-320940D01*
X526079Y-320415D01*
X526627Y-320100D01*
X527175D01*
X527724Y-320310D01*
X528194Y-320835D01*
G01X532222Y-320100D02*
X534102D01*
G01X533162D02*
Y-326400D01*
G01X532222D02*
X534102D01*
G01X537504D02*
X539462Y-320100D01*
X541420Y-326400D01*
G01X540715Y-324195D02*
X538209D01*
G01X543960Y-326400D02*
Y-320100D01*
X547564Y-326400D01*
Y-320100D01*
G01X552532Y-323250D02*
X554099D01*
Y-325140D01*
X553629Y-325770D01*
X553080Y-326190D01*
X552297Y-326400D01*
X551514Y-326190D01*
X550965Y-325770D01*
X550495Y-325140D01*
X550182Y-324405D01*
X550025Y-323565D01*
Y-322830D01*
X550182Y-322200D01*
X550495Y-321465D01*
X550965Y-320835D01*
X551435Y-320415D01*
X552062Y-320100D01*
X552610D01*
X553237Y-320310D01*
X553707Y-320730D01*
G01X558205Y-327555D02*
X558519Y-326190D01*
G01X564662Y-320100D02*
Y-326400D01*
G01X562860Y-320100D02*
X566464D01*
G01X569004Y-326400D02*
X570962Y-320100D01*
X572920Y-326400D01*
G01X572215Y-324195D02*
X569709D01*
G01X577262Y-326400D02*
X576635Y-326295D01*
X576087Y-325875D01*
X575617Y-325245D01*
X575304Y-324510D01*
X575147Y-323670D01*
Y-322830D01*
X575304Y-321990D01*
X575617Y-321255D01*
X576087Y-320625D01*
X576635Y-320205D01*
X577262Y-320100D01*
X577889Y-320205D01*
X578437Y-320625D01*
X578907Y-321255D01*
X579220Y-321990D01*
X579377Y-322830D01*
Y-323670D01*
X579220Y-324510D01*
X578907Y-325245D01*
X578437Y-325875D01*
X577889Y-326295D01*
X577262Y-326400D01*
G01X589862D02*
Y-323565D01*
X588295Y-320100D01*
G01X591429D02*
X589862Y-323565D01*
G01X594439Y-320100D02*
Y-324615D01*
X594752Y-325560D01*
X595379Y-326190D01*
X596162Y-326400D01*
X596945Y-326190D01*
X597572Y-325560D01*
X597885Y-324615D01*
Y-320100D01*
G01X600504Y-326400D02*
X602462Y-320100D01*
X604420Y-326400D01*
G01X603715Y-324195D02*
X601209D01*
G01X606960Y-326400D02*
Y-320100D01*
X610564Y-326400D01*
Y-320100D01*
G01X455760Y-316400D02*
Y-310100D01*
X459364Y-316400D01*
Y-310100D01*
G01X463862Y-316400D02*
X463235Y-316295D01*
X462687Y-315875D01*
X462217Y-315245D01*
X461904Y-314510D01*
X461747Y-313670D01*
Y-312830D01*
X461904Y-311990D01*
X462217Y-311255D01*
X462687Y-310625D01*
X463235Y-310205D01*
X463862Y-310100D01*
X464489Y-310205D01*
X465037Y-310625D01*
X465507Y-311255D01*
X465820Y-311990D01*
X465977Y-312830D01*
Y-313670D01*
X465820Y-314510D01*
X465507Y-315245D01*
X465037Y-315875D01*
X464489Y-316295D01*
X463862Y-316400D01*
G01X470162Y-316610D02*
X470005Y-316505D01*
Y-316295D01*
X470162Y-316190D01*
X470319Y-316295D01*
Y-316505D01*
X470162Y-316610D01*
G01X476462Y-316400D02*
Y-310100D01*
X475522Y-311360D01*
G01Y-316400D02*
X477402D01*
G01X482762D02*
X483310Y-316295D01*
X483937Y-315980D01*
X484329Y-315455D01*
X484485Y-314720D01*
X484329Y-313985D01*
X483859Y-313355D01*
X483154Y-313040D01*
X482370D01*
X481900Y-312830D01*
X481509Y-312305D01*
X481352Y-311570D01*
X481587Y-310835D01*
X482135Y-310310D01*
X482762Y-310100D01*
X483389Y-310310D01*
X483937Y-310835D01*
X484172Y-311570D01*
X484015Y-312305D01*
X483624Y-312830D01*
X483154Y-313040D01*
X482370D01*
X481665Y-313355D01*
X481195Y-313985D01*
X481039Y-314720D01*
X481195Y-315455D01*
X481587Y-315980D01*
X482214Y-316295D01*
X482762Y-316400D01*
G01X489062D02*
X489610Y-316295D01*
X490237Y-315980D01*
X490629Y-315455D01*
X490785Y-314720D01*
X490629Y-313985D01*
X490159Y-313355D01*
X489454Y-313040D01*
X488670D01*
X488200Y-312830D01*
X487809Y-312305D01*
X487652Y-311570D01*
X487887Y-310835D01*
X488435Y-310310D01*
X489062Y-310100D01*
X489689Y-310310D01*
X490237Y-310835D01*
X490472Y-311570D01*
X490315Y-312305D01*
X489924Y-312830D01*
X489454Y-313040D01*
X488670D01*
X487965Y-313355D01*
X487495Y-313985D01*
X487339Y-314720D01*
X487495Y-315455D01*
X487887Y-315980D01*
X488514Y-316295D01*
X489062Y-316400D01*
G01X495205Y-317555D02*
X495519Y-316190D01*
G01X499312Y-310100D02*
X500409Y-316400D01*
X501662Y-310100D01*
X502915Y-316400D01*
X504012Y-310100D01*
G01X509529Y-316400D02*
X506395D01*
Y-310100D01*
X509529D01*
G01X508275Y-313145D02*
X506395D01*
G01X512460Y-316400D02*
Y-310100D01*
X516064Y-316400D01*
Y-310100D01*
G01X525217Y-316400D02*
Y-310100D01*
G01X528507D02*
Y-316400D01*
G01Y-313250D02*
X525217D01*
G01X530812Y-310100D02*
X531909Y-316400D01*
X533162Y-310100D01*
X534415Y-316400D01*
X535512Y-310100D01*
G01X537504Y-316400D02*
X539462Y-310100D01*
X541420Y-316400D01*
G01X540715Y-314195D02*
X538209D01*
G01X550574Y-311150D02*
X551044Y-310520D01*
X551592Y-310205D01*
X552219Y-310100D01*
X553002Y-310310D01*
X553550Y-310835D01*
X553707Y-311465D01*
X553629Y-312095D01*
X553315Y-312620D01*
X551749Y-313670D01*
X551044Y-314405D01*
X550574Y-315455D01*
X550417Y-316400D01*
X553707D01*
G01X556560D02*
Y-310100D01*
X560164Y-316400D01*
Y-310100D01*
G01X562939Y-316400D02*
Y-310100D01*
X564505D01*
X565132Y-310415D01*
X565602Y-310835D01*
X565994Y-311465D01*
X566307Y-312200D01*
X566385Y-313250D01*
X566307Y-314300D01*
X565994Y-315035D01*
X565602Y-315665D01*
X565132Y-316085D01*
X564505Y-316400D01*
X562939D01*
G01X575695D02*
Y-310100D01*
X577654D01*
X578280Y-310415D01*
X578672Y-310835D01*
X578829Y-311675D01*
X578672Y-312515D01*
X578202Y-313040D01*
X577654Y-313355D01*
X575695D01*
G01X577654D02*
X578829Y-316400D01*
G01X581839D02*
Y-310100D01*
X583405D01*
X584032Y-310415D01*
X584502Y-310835D01*
X584894Y-311465D01*
X585207Y-312200D01*
X585285Y-313250D01*
X585207Y-314300D01*
X584894Y-315035D01*
X584502Y-315665D01*
X584032Y-316085D01*
X583405Y-316400D01*
X581839D01*
G01X589862Y-316610D02*
X589705Y-316505D01*
Y-316295D01*
X589862Y-316190D01*
X590019Y-316295D01*
Y-316505D01*
X589862Y-316610D01*
G01X479862Y-303700D02*
X477342Y-303283D01*
X475137Y-301617D01*
X473247Y-299117D01*
X471987Y-296200D01*
X471357Y-292867D01*
Y-289533D01*
X471987Y-286200D01*
X473247Y-283283D01*
X475137Y-280784D01*
X477342Y-279117D01*
X479862Y-278700D01*
X482382Y-279117D01*
X484587Y-280784D01*
X486477Y-283283D01*
X487737Y-286200D01*
X488367Y-289533D01*
Y-292867D01*
X487737Y-296200D01*
X486477Y-299117D01*
X484587Y-301617D01*
X482382Y-303283D01*
X479862Y-303700D01*
G01X482382Y-297033D02*
X486162Y-303700D01*
G01X499707Y-287034D02*
Y-298700D01*
X500967Y-301617D01*
X502857Y-303283D01*
X505062Y-303700D01*
X507267Y-303283D01*
X509157Y-301617D01*
X510417Y-298700D01*
G01Y-303700D02*
Y-287034D01*
G01X535932Y-303700D02*
Y-287034D01*
G01Y-289950D02*
X534672Y-288284D01*
X532782Y-287450D01*
X530577Y-287034D01*
X528372Y-287867D01*
X526482Y-289533D01*
X525222Y-292034D01*
X524592Y-295367D01*
X525222Y-298700D01*
X526482Y-301201D01*
X528372Y-302867D01*
X530577Y-303700D01*
X532782Y-303283D01*
X534672Y-302034D01*
X535932Y-300367D01*
G01X550107Y-303700D02*
Y-287034D01*
G01Y-291200D02*
X551367Y-289117D01*
X553257Y-287450D01*
X555777Y-287034D01*
X557982Y-287450D01*
X559872Y-289117D01*
X560817Y-292034D01*
Y-303700D01*
G01X580662Y-278700D02*
Y-303700D01*
G01X576252Y-287034D02*
X585072D01*
G01X611532Y-303700D02*
Y-287034D01*
G01Y-289950D02*
X610272Y-288284D01*
X608382Y-287450D01*
X606177Y-287034D01*
X603972Y-287867D01*
X602082Y-289533D01*
X600822Y-292034D01*
X600192Y-295367D01*
X600822Y-298700D01*
X602082Y-301201D01*
X603972Y-302867D01*
X606177Y-303700D01*
X608382Y-303283D01*
X610272Y-302034D01*
X611532Y-300367D01*
G01X651212Y-283400D02*
Y-291400D01*
X655212D01*
G01X663012D02*
Y-286067D01*
G01Y-287000D02*
X662612Y-286467D01*
X662012Y-286200D01*
X661312Y-286067D01*
X660612Y-286333D01*
X660012Y-286867D01*
X659612Y-287667D01*
X659412Y-288733D01*
X659612Y-289800D01*
X660012Y-290600D01*
X660612Y-291133D01*
X661312Y-291400D01*
X662012Y-291267D01*
X662612Y-290867D01*
X663012Y-290334D01*
G01X667112Y-293800D02*
X667712Y-294067D01*
X668512Y-293800D01*
X669012Y-293267D01*
X669412Y-292600D01*
X670012Y-290467D01*
X671312Y-286067D01*
G01X668112D02*
X670012Y-290467D01*
G01X675712Y-287800D02*
X678912D01*
X678612Y-286867D01*
X678112Y-286333D01*
X677412Y-286067D01*
X676712Y-286200D01*
X676112Y-286600D01*
X675712Y-287533D01*
X675512Y-288334D01*
Y-289133D01*
X675712Y-289933D01*
X676212Y-290733D01*
X676812Y-291267D01*
X677512Y-291400D01*
X678212Y-291133D01*
X678912Y-290334D01*
G01X683812Y-291400D02*
Y-286067D01*
G01Y-287133D02*
X684312Y-286600D01*
X684812Y-286200D01*
X685512Y-286067D01*
X686012Y-286200D01*
X686612Y-286600D01*
G01X673512Y-333400D02*
X675912D01*
G01X674712D02*
Y-341400D01*
G01X673512D02*
X675912D01*
G01X681312D02*
Y-336067D01*
G01Y-337133D02*
X681812Y-336600D01*
X682312Y-336200D01*
X683012Y-336067D01*
X683512Y-336200D01*
X684112Y-336600D01*
G01X689212Y-337800D02*
X692412D01*
X692112Y-336867D01*
X691612Y-336333D01*
X690912Y-336067D01*
X690212Y-336200D01*
X689612Y-336600D01*
X689212Y-337533D01*
X689012Y-338334D01*
Y-339133D01*
X689212Y-339933D01*
X689712Y-340733D01*
X690312Y-341267D01*
X691012Y-341400D01*
X691712Y-341133D01*
X692412Y-340334D01*
G01X697012Y-341400D02*
Y-336067D01*
G01Y-337400D02*
X697412Y-336733D01*
X698012Y-336200D01*
X698812Y-336067D01*
X699512Y-336200D01*
X700112Y-336733D01*
X700412Y-337667D01*
Y-341400D01*
G01X705212Y-337800D02*
X708412D01*
X708112Y-336867D01*
X707612Y-336333D01*
X706912Y-336067D01*
X706212Y-336200D01*
X705612Y-336600D01*
X705212Y-337533D01*
X705012Y-338334D01*
Y-339133D01*
X705212Y-339933D01*
X705712Y-340733D01*
X706312Y-341267D01*
X707012Y-341400D01*
X707712Y-341133D01*
X708412Y-340334D01*
G01X664612Y-316400D02*
Y-308400D01*
X667212Y-315067D01*
X669812Y-308400D01*
Y-316400D01*
G01X672712D02*
X675212Y-308400D01*
X677712Y-316400D01*
G01X676812Y-313600D02*
X673612D01*
G01X681112Y-315334D02*
X681912Y-316000D01*
X682812Y-316400D01*
X683612D01*
X684412Y-316000D01*
X685012Y-315334D01*
X685312Y-314400D01*
X685112Y-313467D01*
X684612Y-312667D01*
X683712Y-312133D01*
X682512Y-311867D01*
X681812Y-311333D01*
X681512Y-310400D01*
X681712Y-309467D01*
X682212Y-308800D01*
X682912Y-308400D01*
X683612D01*
X684312Y-308667D01*
X684912Y-309333D01*
G01X689012Y-316400D02*
Y-308400D01*
G01X692812D02*
X689012Y-313334D01*
G01X693412Y-316400D02*
X690712Y-311067D01*
G01X697912Y-313733D02*
X700512D01*
G01X708012Y-312133D02*
X708412Y-311733D01*
X708712Y-311067D01*
X708912Y-310133D01*
X708712Y-309333D01*
X708312Y-308800D01*
X707612Y-308400D01*
X704912D01*
Y-316400D01*
X708212D01*
X708912Y-315867D01*
X709312Y-315067D01*
X709512Y-314133D01*
X709312Y-313200D01*
X708712Y-312400D01*
X708012Y-312133D01*
X704912D01*
G01X715212Y-316400D02*
X714412Y-316267D01*
X713712Y-315733D01*
X713112Y-314933D01*
X712712Y-314000D01*
X712512Y-312933D01*
Y-311867D01*
X712712Y-310800D01*
X713112Y-309867D01*
X713712Y-309067D01*
X714412Y-308533D01*
X715212Y-308400D01*
X716012Y-308533D01*
X716712Y-309067D01*
X717312Y-309867D01*
X717712Y-310800D01*
X717912Y-311867D01*
Y-312933D01*
X717712Y-314000D01*
X717312Y-314933D01*
X716712Y-315733D01*
X716012Y-316267D01*
X715212Y-316400D01*
G01X723212Y-308400D02*
Y-316400D01*
G01X720912Y-308400D02*
X725512D01*
G01X777812Y-334733D02*
X778412Y-333933D01*
X779112Y-333533D01*
X779912Y-333400D01*
X780912Y-333667D01*
X781612Y-334333D01*
X781812Y-335133D01*
X781712Y-335934D01*
X781312Y-336600D01*
X779312Y-337933D01*
X778412Y-338867D01*
X777812Y-340200D01*
X777612Y-341400D01*
X781812D01*
G01X787712Y-333400D02*
X786912Y-333667D01*
X786312Y-334333D01*
X785912Y-335133D01*
X785612Y-336200D01*
X785512Y-337400D01*
X785612Y-338600D01*
X785912Y-339667D01*
X786312Y-340467D01*
X786912Y-341133D01*
X787712Y-341400D01*
X788512Y-341133D01*
X789112Y-340467D01*
X789512Y-339667D01*
X789812Y-338600D01*
X789912Y-337400D01*
X789812Y-336200D01*
X789512Y-335133D01*
X789112Y-334333D01*
X788512Y-333667D01*
X787712Y-333400D01*
G01X795712Y-341400D02*
Y-333400D01*
X794512Y-335000D01*
G01Y-341400D02*
X796912D01*
G01X801812Y-334733D02*
X802412Y-333933D01*
X803112Y-333533D01*
X803912Y-333400D01*
X804912Y-333667D01*
X805612Y-334333D01*
X805812Y-335133D01*
X805712Y-335934D01*
X805312Y-336600D01*
X803312Y-337933D01*
X802412Y-338867D01*
X801812Y-340200D01*
X801612Y-341400D01*
X805812D01*
G01X809912Y-341667D02*
X813512Y-333400D01*
G01X819712Y-341400D02*
Y-333400D01*
X818512Y-335000D01*
G01Y-341400D02*
X820912D01*
G01X827712Y-333400D02*
X826912Y-333667D01*
X826312Y-334333D01*
X825912Y-335133D01*
X825612Y-336200D01*
X825512Y-337400D01*
X825612Y-338600D01*
X825912Y-339667D01*
X826312Y-340467D01*
X826912Y-341133D01*
X827712Y-341400D01*
X828512Y-341133D01*
X829112Y-340467D01*
X829512Y-339667D01*
X829812Y-338600D01*
X829912Y-337400D01*
X829812Y-336200D01*
X829512Y-335133D01*
X829112Y-334333D01*
X828512Y-333667D01*
X827712Y-333400D01*
G01X833912Y-341667D02*
X837512Y-333400D01*
G01X841512Y-339800D02*
X842112Y-340733D01*
X842912Y-341267D01*
X843812Y-341400D01*
X844612Y-341267D01*
X845412Y-340600D01*
X845912Y-339800D01*
X846012Y-339000D01*
X845812Y-338067D01*
X845112Y-337400D01*
X844412Y-337133D01*
X843512D01*
G01X844412D02*
X845012Y-336733D01*
X845512Y-336067D01*
X845712Y-335267D01*
X845512Y-334467D01*
X845012Y-333800D01*
X844112Y-333400D01*
X843212Y-333533D01*
X842312Y-334067D01*
G01X851712Y-341400D02*
Y-333400D01*
X850512Y-335000D01*
G01Y-341400D02*
X852912D01*
G01X777512Y-316400D02*
Y-308400D01*
X779512D01*
X780312Y-308800D01*
X780912Y-309333D01*
X781412Y-310133D01*
X781812Y-311067D01*
X781912Y-312400D01*
X781812Y-313733D01*
X781412Y-314667D01*
X780912Y-315467D01*
X780312Y-316000D01*
X779512Y-316400D01*
X777512D01*
G01X785212D02*
X787712Y-308400D01*
X790212Y-316400D01*
G01X789312Y-313600D02*
X786112D01*
G01X795712Y-308400D02*
X794912Y-308667D01*
X794312Y-309333D01*
X793912Y-310133D01*
X793612Y-311200D01*
X793512Y-312400D01*
X793612Y-313600D01*
X793912Y-314667D01*
X794312Y-315467D01*
X794912Y-316133D01*
X795712Y-316400D01*
X796512Y-316133D01*
X797112Y-315467D01*
X797512Y-314667D01*
X797812Y-313600D01*
X797912Y-312400D01*
X797812Y-311200D01*
X797512Y-310133D01*
X797112Y-309333D01*
X796512Y-308667D01*
X795712Y-308400D01*
G01X803712D02*
Y-316400D01*
G01X801412Y-308400D02*
X806012D01*
G01X809812Y-313067D02*
X810512Y-312133D01*
X811112Y-311600D01*
X811912Y-311333D01*
X812612Y-311600D01*
X813112Y-312133D01*
X813512Y-312933D01*
X813612Y-313867D01*
X813512Y-314667D01*
X813112Y-315467D01*
X812512Y-316133D01*
X811812Y-316400D01*
X811012Y-316133D01*
X810312Y-315334D01*
X809912Y-314133D01*
X809812Y-312800D01*
X810012Y-311067D01*
X810312Y-310133D01*
X810812Y-309200D01*
X811512Y-308533D01*
X812212Y-308400D01*
X812912Y-308667D01*
X813412Y-309333D01*
G01X817112Y-316400D02*
Y-308400D01*
X819712Y-315067D01*
X822312Y-308400D01*
Y-316400D01*
G01X827712Y-308400D02*
Y-316400D01*
G01X825412Y-308400D02*
X830012D01*
G01X833612Y-316400D02*
Y-308400D01*
G01X837812D02*
Y-316400D01*
G01Y-312400D02*
X833612D01*
G01X843712Y-316400D02*
X844412Y-316267D01*
X845212Y-315867D01*
X845712Y-315200D01*
X845912Y-314267D01*
X845712Y-313334D01*
X845112Y-312533D01*
X844212Y-312133D01*
X843212D01*
X842612Y-311867D01*
X842112Y-311200D01*
X841912Y-310267D01*
X842212Y-309333D01*
X842912Y-308667D01*
X843712Y-308400D01*
X844512Y-308667D01*
X845212Y-309333D01*
X845512Y-310267D01*
X845312Y-311200D01*
X844812Y-311867D01*
X844212Y-312133D01*
X843212D01*
X842312Y-312533D01*
X841712Y-313334D01*
X841512Y-314267D01*
X841712Y-315200D01*
X842212Y-315867D01*
X843012Y-316267D01*
X843712Y-316400D01*
G01X853912Y-309067D02*
X853312Y-308667D01*
X852612Y-308400D01*
X851812D01*
X850912Y-308800D01*
X850212Y-309467D01*
X849712Y-310267D01*
X849312Y-311600D01*
X849212Y-312800D01*
X849412Y-314000D01*
X849712Y-314800D01*
X850312Y-315600D01*
X851012Y-316133D01*
X851712Y-316400D01*
X852412D01*
X853112Y-316133D01*
X853712Y-315733D01*
X854212Y-315200D01*
G01X859712Y-308400D02*
X858912Y-308667D01*
X858312Y-309333D01*
X857912Y-310133D01*
X857612Y-311200D01*
X857512Y-312400D01*
X857612Y-313600D01*
X857912Y-314667D01*
X858312Y-315467D01*
X858912Y-316133D01*
X859712Y-316400D01*
X860512Y-316133D01*
X861112Y-315467D01*
X861512Y-314667D01*
X861812Y-313600D01*
X861912Y-312400D01*
X861812Y-311200D01*
X861512Y-310133D01*
X861112Y-309333D01*
X860512Y-308667D01*
X859712Y-308400D01*
G01X799712Y-283400D02*
Y-291400D01*
G01X797412Y-283400D02*
X802012D01*
G01X805812Y-288067D02*
X806512Y-287133D01*
X807112Y-286600D01*
X807912Y-286333D01*
X808612Y-286600D01*
X809112Y-287133D01*
X809512Y-287933D01*
X809612Y-288867D01*
X809512Y-289667D01*
X809112Y-290467D01*
X808512Y-291133D01*
X807812Y-291400D01*
X807012Y-291133D01*
X806312Y-290334D01*
X805912Y-289133D01*
X805812Y-287800D01*
X806012Y-286067D01*
X806312Y-285133D01*
X806812Y-284200D01*
X807512Y-283533D01*
X808212Y-283400D01*
X808912Y-283667D01*
X809412Y-284333D01*
G01X813112Y-291400D02*
Y-283400D01*
X815712Y-290067D01*
X818312Y-283400D01*
Y-291400D01*
G01X820712Y-294067D02*
X826712D01*
G01X831712Y-283400D02*
Y-291400D01*
G01X829412Y-283400D02*
X834012D01*
G01X838312Y-291400D02*
Y-286067D01*
G01Y-287133D02*
X838812Y-286600D01*
X839312Y-286200D01*
X840012Y-286067D01*
X840512Y-286200D01*
X841112Y-286600D01*
G01X849512Y-291400D02*
Y-286067D01*
G01Y-287000D02*
X849112Y-286467D01*
X848512Y-286200D01*
X847812Y-286067D01*
X847112Y-286333D01*
X846512Y-286867D01*
X846112Y-287667D01*
X845912Y-288733D01*
X846112Y-289800D01*
X846512Y-290600D01*
X847112Y-291133D01*
X847812Y-291400D01*
X848512Y-291267D01*
X849112Y-290867D01*
X849512Y-290334D01*
G01X853612Y-293800D02*
X854212Y-294067D01*
X855012Y-293800D01*
X855512Y-293267D01*
X855912Y-292600D01*
X856512Y-290467D01*
X857812Y-286067D01*
G01X854612D02*
X856512Y-290467D01*
G01X860712Y-294067D02*
X866712D01*
G01X872512Y-287133D02*
X872912Y-286733D01*
X873212Y-286067D01*
X873412Y-285133D01*
X873212Y-284333D01*
X872812Y-283800D01*
X872112Y-283400D01*
X869412D01*
Y-291400D01*
X872712D01*
X873412Y-290867D01*
X873812Y-290067D01*
X874012Y-289133D01*
X873812Y-288200D01*
X873212Y-287400D01*
X872512Y-287133D01*
X869412D01*
G01X877712Y-291400D02*
Y-283400D01*
X880112D01*
X880912Y-283800D01*
X881512Y-284733D01*
X881712Y-285800D01*
X881512Y-286867D01*
X881012Y-287667D01*
X880112Y-288067D01*
X877712D01*
G01X896912Y-334067D02*
X896312Y-333667D01*
X895612Y-333400D01*
X894812D01*
X893912Y-333800D01*
X893212Y-334467D01*
X892712Y-335267D01*
X892312Y-336600D01*
X892212Y-337800D01*
X892412Y-339000D01*
X892712Y-339800D01*
X893312Y-340600D01*
X894012Y-341133D01*
X894712Y-341400D01*
X895412D01*
X896112Y-341133D01*
X896712Y-340733D01*
X897212Y-340200D01*
G01X922212Y-341400D02*
Y-333400D01*
X921012Y-335000D01*
G01Y-341400D02*
X923412D01*
G01X928312Y-338067D02*
X929012Y-337133D01*
X929612Y-336600D01*
X930412Y-336333D01*
X931112Y-336600D01*
X931612Y-337133D01*
X932012Y-337933D01*
X932112Y-338867D01*
X932012Y-339667D01*
X931612Y-340467D01*
X931012Y-341133D01*
X930312Y-341400D01*
X929512Y-341133D01*
X928812Y-340334D01*
X928412Y-339133D01*
X928312Y-337800D01*
X928512Y-336067D01*
X928812Y-335133D01*
X929312Y-334200D01*
X930012Y-333533D01*
X930712Y-333400D01*
X931412Y-333667D01*
X931912Y-334333D01*
G54D17*
X44528Y41339D03*
Y53150D03*
X56339Y41339D03*
Y53150D03*
X44528Y64961D03*
Y76772D03*
X56339Y64961D03*
Y76772D03*
X44528Y88583D03*
Y100394D03*
X56339Y88583D03*
Y100394D03*
X44528Y112205D03*
Y124016D03*
X56339Y112205D03*
Y124016D03*
X44528Y135827D03*
G54D35*
X468859Y115666D03*
Y141650D03*
X488859Y115666D03*
X478859D03*
X483859Y125666D03*
X473859D03*
X478859Y141650D03*
X488859D03*
X473859Y151650D03*
X483859D03*
X498859Y115666D03*
X503859Y125666D03*
X493859D03*
X498859Y141650D03*
X493859Y151650D03*
X1338938Y115666D03*
X1343938Y125666D03*
X1338938Y141650D03*
X1343938Y151650D03*
X1358938Y115666D03*
X1348938D03*
X1363938Y125666D03*
X1353938D03*
X1348938Y141650D03*
X1358938D03*
X1353938Y151650D03*
X1363938D03*
X1368938Y115666D03*
X1373938Y125666D03*
X1368938Y141650D03*
G54D26*
X343780Y11810D03*
Y19684D03*
Y27558D03*
X335906Y11810D03*
Y19684D03*
Y27558D03*
X343780Y43306D03*
Y51180D03*
X335906Y43306D03*
Y51180D03*
X343780Y59054D03*
X367402Y11810D03*
Y19684D03*
Y27558D03*
X359528Y11810D03*
Y19684D03*
Y27558D03*
X367402Y43306D03*
Y51180D03*
X359528Y43306D03*
Y51180D03*
X367402Y59054D03*
X359528D03*
X1205984Y11810D03*
Y19684D03*
Y27558D03*
Y43306D03*
Y51180D03*
X1213858Y11810D03*
Y19684D03*
Y27558D03*
X1229606Y11810D03*
Y19684D03*
Y27558D03*
Y43306D03*
Y51180D03*
X1213858Y43306D03*
Y51180D03*
X1229606Y59054D03*
X1213858D03*
X1237480Y11810D03*
Y19684D03*
Y27558D03*
Y43306D03*
Y51180D03*
Y59054D03*
G54D36*
X452875Y131650D03*
X455867Y153658D03*
X452875Y194642D03*
X516851Y140666D03*
X519843Y115666D03*
Y194642D03*
X1322954Y131650D03*
Y194642D03*
X1325946Y153658D03*
X1389922Y115666D03*
X1386930Y140666D03*
X1389922Y194642D03*
G54D27*
X351654Y37400D03*
X1221732D03*
G54D18*
X56339Y135827D03*
G54D37*
X463859Y176650D03*
X508859D03*
X1333938D03*
X1378938D03*
G54D19*
X62521Y191536D03*
X102521D03*
X142521D03*
X182521D03*
G54D28*
X335906Y59054D03*
X1205984D03*
G54D29*
X392776Y32264D03*
X383642Y50375D03*
Y70060D03*
Y88564D03*
X411673Y32264D03*
X430571D03*
X439744Y50375D03*
Y70060D03*
Y88564D03*
X532934Y50375D03*
Y70060D03*
Y88564D03*
X542068Y32264D03*
X560965D03*
X579863D03*
X589036Y50375D03*
Y70060D03*
Y88564D03*
X1262855Y32264D03*
X1253721Y50375D03*
Y70060D03*
Y88564D03*
X1281752Y32264D03*
X1300650D03*
X1309823Y50375D03*
Y70060D03*
Y88564D03*
X1412146Y32264D03*
X1403012Y50375D03*
Y70060D03*
Y88564D03*
X1431043Y32264D03*
X1449941D03*
X1459114Y50375D03*
Y70060D03*
Y88564D03*
G54D38*
X506024Y8268D03*
X688543D03*
X1376103D03*
X1558622D03*
G54D39*
X503859Y151650D03*
X1373938D03*
M02*
